# S9S_MB_2U (Grand Teton) — schematic parts with pin connectivity, parts 1033–1164 of 6093; source: Cadence DE-HDL packaged netlist (pstxprt.dat, pstxnet.dat, pstchip.dat)

C1517  Q_CAP_DIFFBUS  DIFF BUS_0.22UF 6.3V 20% X6S  pkg C0201  page 177 : 1 = P5E_CPU1_PE3_TX_C_DP<15> ; 2 = P5E_CPU1_PE3_TX_DP<15>
C1518  Q_CAP_DIFFBUS  DIFF BUS_0.22UF 6.3V 20% X6S  pkg C0201  page 177 : 1 = P5E_CPU1_PE3_TX_C_DN<14> ; 2 = P5E_CPU1_PE3_TX_DN<14>
C1519  Q_CAP_DIFFBUS  DIFF BUS_0.22UF 6.3V 20% X6S  pkg C0201  page 177 : 1 = P5E_CPU1_PE3_TX_C_DP<14> ; 2 = P5E_CPU1_PE3_TX_DP<14>
C1520  Q_CAP_DIFFBUS  DIFF BUS_0.22UF 6.3V 20% X6S  pkg C0201  page 177 : 1 = P5E_CPU1_PE3_TX_C_DN<13> ; 2 = P5E_CPU1_PE3_TX_DN<13>
C1521  Q_CAP_DIFFBUS  DIFF BUS_0.22UF 6.3V 20% X6S  pkg C0201  page 177 : 1 = P5E_CPU1_PE3_TX_C_DP<13> ; 2 = P5E_CPU1_PE3_TX_DP<13>
C1522  Q_CAP_DIFFBUS  DIFF BUS_0.22UF 6.3V 20% X6S  pkg C0201  page 177 : 1 = P5E_CPU1_PE3_TX_C_DN<12> ; 2 = P5E_CPU1_PE3_TX_DN<12>
C1523  Q_CAP_DIFFBUS  DIFF BUS_0.22UF 6.3V 20% X6S  pkg C0201  page 177 : 1 = P5E_CPU1_PE3_TX_C_DP<12> ; 2 = P5E_CPU1_PE3_TX_DP<12>
C1524  Q_CAP_DIFFBUS  DIFF BUS_0.22UF 6.3V 20% X6S  pkg C0201  page 177 : 1 = P5E_CPU1_PE3_TX_C_DN<11> ; 2 = P5E_CPU1_PE3_TX_DN<11>
C1525  Q_CAP_DIFFBUS  DIFF BUS_0.22UF 6.3V 20% X6S  pkg C0201  page 177 : 1 = P5E_CPU1_PE3_TX_C_DP<11> ; 2 = P5E_CPU1_PE3_TX_DP<11>
C1526  Q_CAP_DIFFBUS  DIFF BUS_0.22UF 6.3V 20% X6S  pkg C0201  page 177 : 1 = P5E_CPU1_PE3_TX_C_DN<10> ; 2 = P5E_CPU1_PE3_TX_DN<10>
C1527  Q_CAP_DIFFBUS  DIFF BUS_0.22UF 6.3V 20% X6S  pkg C0201  page 177 : 1 = P5E_CPU1_PE3_TX_C_DP<10> ; 2 = P5E_CPU1_PE3_TX_DP<10>
C1528  Q_CAP_DIFFBUS  DIFF BUS_0.22UF 6.3V 20% X6S  pkg C0201  page 177 : 1 = P5E_CPU1_PE3_TX_C_DN<9> ; 2 = P5E_CPU1_PE3_TX_DN<9>
C1529  Q_CAP_DIFFBUS  DIFF BUS_0.22UF 6.3V 20% X6S  pkg C0201  page 177 : 1 = P5E_CPU1_PE3_TX_C_DP<9> ; 2 = P5E_CPU1_PE3_TX_DP<9>
C1530  Q_CAP_DIFFBUS  DIFF BUS_0.22UF 6.3V 20% X6S  pkg C0201  page 177 : 1 = P5E_CPU1_PE3_TX_C_DN<8> ; 2 = P5E_CPU1_PE3_TX_DN<8>
C1531  Q_CAP_DIFFBUS  DIFF BUS_0.22UF 6.3V 20% X6S  pkg C0201  page 177 : 1 = P5E_CPU1_PE3_TX_C_DP<8> ; 2 = P5E_CPU1_PE3_TX_DP<8>
C1532  Q_CAP_DIFFBUS  DIFF BUS_0.22UF 6.3V 20% X6S  pkg C0201  page 177 : 1 = P5E_CPU1_PE3_TX_C_DN<7> ; 2 = P5E_CPU1_PE3_TX_DN<7>
C1533  Q_CAP_DIFFBUS  DIFF BUS_0.22UF 6.3V 20% X6S  pkg C0201  page 177 : 1 = P5E_CPU1_PE3_TX_C_DP<7> ; 2 = P5E_CPU1_PE3_TX_DP<7>
C1534  Q_CAP_DIFFBUS  DIFF BUS_0.22UF 6.3V 20% X6S  pkg C0201  page 177 : 1 = P5E_CPU1_PE3_TX_C_DN<6> ; 2 = P5E_CPU1_PE3_TX_DN<6>
C1535  Q_CAP_DIFFBUS  DIFF BUS_0.22UF 6.3V 20% X6S  pkg C0201  page 177 : 1 = P5E_CPU1_PE3_TX_C_DP<6> ; 2 = P5E_CPU1_PE3_TX_DP<6>
C1536  Q_CAP_DIFFBUS  DIFF BUS_0.22UF 6.3V 20% X6S  pkg C0201  page 177 : 1 = P5E_CPU1_PE3_TX_C_DN<5> ; 2 = P5E_CPU1_PE3_TX_DN<5>
C1537  Q_CAP_DIFFBUS  DIFF BUS_0.22UF 6.3V 20% X6S  pkg C0201  page 177 : 1 = P5E_CPU1_PE3_TX_C_DP<5> ; 2 = P5E_CPU1_PE3_TX_DP<5>
C1538  Q_CAP_DIFFBUS  DIFF BUS_0.22UF 6.3V 20% X6S  pkg C0201  page 177 : 1 = P5E_CPU1_PE3_TX_C_DN<4> ; 2 = P5E_CPU1_PE3_TX_DN<4>
C1539  Q_CAP_DIFFBUS  DIFF BUS_0.22UF 6.3V 20% X6S  pkg C0201  page 177 : 1 = P5E_CPU1_PE3_TX_C_DP<4> ; 2 = P5E_CPU1_PE3_TX_DP<4>
C1540  Q_CAP_DIFFBUS  DIFF BUS_0.22UF 6.3V 20% X6S  pkg C0201  page 177 : 1 = P5E_CPU1_PE3_TX_C_DN<3> ; 2 = P5E_CPU1_PE3_TX_DN<3>
C1541  Q_CAP_DIFFBUS  DIFF BUS_0.22UF 6.3V 20% X6S  pkg C0201  page 177 : 1 = P5E_CPU1_PE3_TX_C_DP<3> ; 2 = P5E_CPU1_PE3_TX_DP<3>
C1542  Q_CAP_DIFFBUS  DIFF BUS_0.22UF 6.3V 20% X6S  pkg C0201  page 177 : 1 = P5E_CPU1_PE3_TX_C_DN<2> ; 2 = P5E_CPU1_PE3_TX_DN<2>
C1543  Q_CAP_DIFFBUS  DIFF BUS_0.22UF 6.3V 20% X6S  pkg C0201  page 177 : 1 = P5E_CPU1_PE3_TX_C_DP<2> ; 2 = P5E_CPU1_PE3_TX_DP<2>
C1544  Q_CAP_DIFFBUS  DIFF BUS_0.22UF 6.3V 20% X6S  pkg C0201  page 177 : 1 = P5E_CPU1_PE3_TX_C_DN<1> ; 2 = P5E_CPU1_PE3_TX_DN<1>
C1545  Q_CAP_DIFFBUS  DIFF BUS_0.22UF 6.3V 20% X6S  pkg C0201  page 177 : 1 = P5E_CPU1_PE3_TX_C_DP<1> ; 2 = P5E_CPU1_PE3_TX_DP<1>
C1546  Q_CAP_DIFFBUS  DIFF BUS_0.22UF 6.3V 20% X6S  pkg C0201  page 177 : 1 = P5E_CPU1_PE3_TX_C_DN<0> ; 2 = P5E_CPU1_PE3_TX_DN<0>
C1547  Q_CAP_DIFFBUS  DIFF BUS_0.22UF 6.3V 20% X6S  pkg C0201  page 177 : 1 = P5E_CPU1_PE3_TX_C_DP<0> ; 2 = P5E_CPU1_PE3_TX_DP<0>
C1548  Q_CAP_DIFFBUS  DIFF BUS_0.22UF 6.3V 20% X6S  pkg C0201  page 175 : 1 = P5E_CPU0_PE4_TX_C_DN<15> ; 2 = P5E_CPU0_PE4_TX_DN<15>
C1549  Q_CAP_DIFFBUS  DIFF BUS_0.22UF 6.3V 20% X6S  pkg C0201  page 175 : 1 = P5E_CPU0_PE4_TX_C_DP<15> ; 2 = P5E_CPU0_PE4_TX_DP<15>
C1550  Q_CAP_DIFFBUS  DIFF BUS_0.22UF 6.3V 20% X6S  pkg C0201  page 175 : 1 = P5E_CPU0_PE4_TX_C_DN<14> ; 2 = P5E_CPU0_PE4_TX_DN<14>
C1552  Q_CAP_DIFFBUS  DIFF BUS_0.22UF 6.3V 20% X6S  pkg C0201  page 175 : 1 = P5E_CPU0_PE4_TX_C_DN<13> ; 2 = P5E_CPU0_PE4_TX_DN<13>
C1553  Q_CAP_DIFFBUS  DIFF BUS_0.22UF 6.3V 20% X6S  pkg C0201  page 175 : 1 = P5E_CPU0_PE4_TX_C_DP<13> ; 2 = P5E_CPU0_PE4_TX_DP<13>
C1554  Q_CAP_DIFFBUS  DIFF BUS_0.22UF 6.3V 20% X6S  pkg C0201  page 175 : 1 = P5E_CPU0_PE4_TX_C_DN<12> ; 2 = P5E_CPU0_PE4_TX_DN<12>
C1555  Q_CAP_DIFFBUS  DIFF BUS_0.22UF 6.3V 20% X6S  pkg C0201  page 175 : 1 = P5E_CPU0_PE4_TX_C_DP<12> ; 2 = P5E_CPU0_PE4_TX_DP<12>
C1556  Q_CAP_DIFFBUS  DIFF BUS_0.22UF 6.3V 20% X6S  pkg C0201  page 175 : 1 = P5E_CPU0_PE4_TX_C_DN<11> ; 2 = P5E_CPU0_PE4_TX_DN<11>
C1557  Q_CAP_DIFFBUS  DIFF BUS_0.22UF 6.3V 20% X6S  pkg C0201  page 175 : 1 = P5E_CPU0_PE4_TX_C_DP<11> ; 2 = P5E_CPU0_PE4_TX_DP<11>
C1558  Q_CAP_DIFFBUS  DIFF BUS_0.22UF 6.3V 20% X6S  pkg C0201  page 175 : 1 = P5E_CPU0_PE4_TX_C_DN<10> ; 2 = P5E_CPU0_PE4_TX_DN<10>
C1559  Q_CAP_DIFFBUS  DIFF BUS_0.22UF 6.3V 20% X6S  pkg C0201  page 175 : 1 = P5E_CPU0_PE4_TX_C_DP<10> ; 2 = P5E_CPU0_PE4_TX_DP<10>
C1560  Q_CAP_DIFFBUS  DIFF BUS_0.22UF 6.3V 20% X6S  pkg C0201  page 175 : 1 = P5E_CPU0_PE4_TX_C_DN<9> ; 2 = P5E_CPU0_PE4_TX_DN<9>
C1561  Q_CAP  1UF 25V 10% X6S  pkg C0402  page 306 : 1 = U206_VDD ; 2 = GND
C1562  Q_CAP  1UF 25V 10% EMPTY  pkg C0402  page 306 : 1 = U205_VDD ; 2 = GND
C1563  Q_CAP_DIFFBUS  DIFF BUS_0.22UF 6.3V 20% X6S  pkg C0201  page 175 : 1 = P5E_CPU0_PE4_TX_C_DP<8> ; 2 = P5E_CPU0_PE4_TX_DP<8>
C1564  Q_CAP_DIFFBUS  DIFF BUS_0.22UF 6.3V 20% X6S  pkg C0201  page 175 : 1 = P5E_CPU0_PE4_TX_C_DN<7> ; 2 = P5E_CPU0_PE4_TX_DN<7>
C1565  Q_CAP_DIFFBUS  DIFF BUS_0.22UF 6.3V 20% X6S  pkg C0201  page 175 : 1 = P5E_CPU0_PE4_TX_C_DP<7> ; 2 = P5E_CPU0_PE4_TX_DP<7>
C1566  Q_CAP_DIFFBUS  DIFF BUS_0.22UF 6.3V 20% X6S  pkg C0201  page 175 : 1 = P5E_CPU0_PE4_TX_C_DN<6> ; 2 = P5E_CPU0_PE4_TX_DN<6>
C1567  Q_CAP_DIFFBUS  DIFF BUS_0.22UF 6.3V 20% X6S  pkg C0201  page 175 : 1 = P5E_CPU0_PE4_TX_C_DP<6> ; 2 = P5E_CPU0_PE4_TX_DP<6>
C1568  Q_CAP_DIFFBUS  DIFF BUS_0.22UF 6.3V 20% X6S  pkg C0201  page 175 : 1 = P5E_CPU0_PE4_TX_C_DN<5> ; 2 = P5E_CPU0_PE4_TX_DN<5>
C1569  Q_CAP_DIFFBUS  DIFF BUS_0.22UF 6.3V 20% X6S  pkg C0201  page 175 : 1 = P5E_CPU0_PE4_TX_C_DP<5> ; 2 = P5E_CPU0_PE4_TX_DP<5>
C1570  Q_CAP_DIFFBUS  DIFF BUS_0.22UF 6.3V 20% X6S  pkg C0201  page 175 : 1 = P5E_CPU0_PE4_TX_C_DN<4> ; 2 = P5E_CPU0_PE4_TX_DN<4>
C1571  Q_CAP_DIFFBUS  DIFF BUS_0.22UF 6.3V 20% X6S  pkg C0201  page 175 : 1 = P5E_CPU0_PE4_TX_C_DP<4> ; 2 = P5E_CPU0_PE4_TX_DP<4>
C1572  Q_CAP_DIFFBUS  DIFF BUS_0.22UF 6.3V 20% X6S  pkg C0201  page 175 : 1 = P5E_CPU0_PE4_TX_C_DN<3> ; 2 = P5E_CPU0_PE4_TX_DN<3>
C1573  Q_CAP_DIFFBUS  DIFF BUS_0.22UF 6.3V 20% X6S  pkg C0201  page 175 : 1 = P5E_CPU0_PE4_TX_C_DP<3> ; 2 = P5E_CPU0_PE4_TX_DP<3>
C1574  Q_CAP_DIFFBUS  DIFF BUS_0.22UF 6.3V 20% X6S  pkg C0201  page 175 : 1 = P5E_CPU0_PE4_TX_C_DN<2> ; 2 = P5E_CPU0_PE4_TX_DN<2>
C1575  Q_CAP_DIFFBUS  DIFF BUS_0.22UF 6.3V 20% X6S  pkg C0201  page 175 : 1 = P5E_CPU0_PE4_TX_C_DP<2> ; 2 = P5E_CPU0_PE4_TX_DP<2>
C1576  Q_CAP_DIFFBUS  DIFF BUS_0.22UF 6.3V 20% X6S  pkg C0201  page 175 : 1 = P5E_CPU0_PE4_TX_C_DN<1> ; 2 = P5E_CPU0_PE4_TX_DN<1>
C1577  Q_CAP_DIFFBUS  DIFF BUS_0.22UF 6.3V 20% X6S  pkg C0201  page 175 : 1 = P5E_CPU0_PE4_TX_C_DP<1> ; 2 = P5E_CPU0_PE4_TX_DP<1>
C1578  Q_CAP_DIFFBUS  DIFF BUS_0.22UF 6.3V 20% X6S  pkg C0201  page 175 : 1 = P5E_CPU0_PE4_TX_C_DN<0> ; 2 = P5E_CPU0_PE4_TX_DN<0>
C1579  Q_CAP_DIFFBUS  DIFF BUS_0.22UF 6.3V 20% X6S  pkg C0201  page 175 : 1 = P5E_CPU0_PE4_TX_C_DP<0> ; 2 = P5E_CPU0_PE4_TX_DP<0>
C1592  Q_CAP  0.1UF 25V 10% X7R  pkg 0402  page 191 : 1 = P3V3_AUX ; 2 = GND
C1612  Q_CAP  1UF 25V 10% X6S  pkg C0402  page 197 : 1 = P3V3_AUX ; 2 = GND
C1613  Q_CAP  0.1UF 25V 10% X7R  pkg 0402  page 236 : 1 = P3V3_AUX ; 2 = GND
C1614  Q_CAP  0.1UF 25V 10% X7R  pkg 0402  page 191 : 1 = P3V3_AUX ; 2 = GND
C1619  Q_CAP  0.1UF 25V 10% X7R  pkg 0402  page 224 : 1 = P3V3_AUX ; 2 = GND
C1647  Q_CAP  0.1UF 25V 10% X7R  pkg 0402  page 202 : 1 = P3V3_AUX ; 2 = GND
C1663  Q_CAP  0.1UF 25V 10% X7R  pkg 0402  page 155 : 1 = P3V3_AUX ; 2 = GND
C1664  Q_CAP  0.1UF 25V 10% X7R  pkg 0402  page 239 : 1 = P0V7_JTAG_VREF_2 ; 2 = GND
C1707  Q_CAP  0.1UF 25V 10% X7R  pkg 0402  page 234 : 1 = P3V3_AUX ; 2 = GND
C1708  Q_CAP  0.1UF 25V 10% EMPTY  pkg 0402  page 234 : 1 = P3V3_AUX ; 2 = GND
C1713  Q_CAP  0.1UF 25V 10% X7R  pkg 0402  page 227 : 1 = P3V3_AUX ; 2 = GND
C1751  Q_CAP  0.1UF 25V 10% X7R  pkg 0402  page 245 : 1 = P3V3_AUX ; 2 = GND
C1754  Q_CAP  1000PF 50V 5% EMPTY  pkg 0402  page 148 : 1 = FM_SWB_BIC_READY_ISO_N ; 2 = GND
C1756  Q_CAP  1000PF 50V 5% EMPTY  pkg 0402  page 148 : 1 = FM_GPU_PWRGD_ISO ; 2 = GND
C1757  Q_CAP  0.1UF 25V 10% EMPTY  pkg 0402  page 250 : 1 = P3V3_MAX11617_VDD ; 2 = GND
C1766  Q_CAP  0.1UF 25V 10% X7R  pkg 0402  page 234 : 1 = P3V3_AUX ; 2 = GND
C1767  Q_CAP  10UF 16V 10% EMPTY  pkg C0805  page 250 : 1 = MAX11617_VREF ; 2 = GND
C1768  Q_CAP  10UF 16V 10% EMPTY  pkg C0805  page 250 : 1 = P3V3_MAX11617_VDD ; 2 = GND
C1769  Q_CAP  0.1UF 25V 10% X7R  pkg 0402  page 151 : 1 = P3V3_AUX ; 2 = GND
C1770  Q_CAP  0.1UF 25V 10% X7R  pkg 0402  page 151 : 1 = P3V3_AUX ; 2 = GND
C1772  Q_CAP  1000PF 50V 5% EMPTY  pkg 0402  page 148 : 1 = RST_BMC_FROM_SWB_ISO_N ; 2 = GND
C1773  Q_CAP  1000PF 50V 5% EMPTY  pkg 0402  page 148 : 1 = BIC_MONITER_ISO ; 2 = GND
C1774  Q_CAP  1000PF 50V 5% EMPTY  pkg 0402  page 148 : 1 = FM_SWB_PWRGD_ISO ; 2 = GND
C1775  Q_CAP  0.1UF 25V 10% X7R  pkg 0402  page 246 : 1 = P3V3_AUX ; 2 = GND
C1791  Q_CAP_DIFFBUS  DIFF BUS_0.22UF 6.3V 20% X6S  pkg C0201  page 178 : 1 = DMI_CPU0_PCH_TX_C_DP<7> ; 2 = DMI_CPU0_PCH_TX_DP<7>
C1792  Q_CAP_DIFFBUS  DIFF BUS_0.22UF 6.3V 20% X6S  pkg C0201  page 175 : 1 = P5E_CPU0_PE4_TX_C_DP<14> ; 2 = P5E_CPU0_PE4_TX_DP<14>
C1793  Q_CAP_DIFFBUS  DIFF BUS_0.22UF 6.3V 20% X6S  pkg C0201  page 175 : 1 = P5E_CPU0_PE4_TX_C_DP<9> ; 2 = P5E_CPU0_PE4_TX_DP<9>
C1794  Q_CAP_DIFFBUS  DIFF BUS_0.22UF 6.3V 20% X6S  pkg C0201  page 175 : 1 = P5E_CPU0_PE4_TX_C_DN<8> ; 2 = P5E_CPU0_PE4_TX_DN<8>
C1796  Q_CAP  0.1UF 25V 10% X7R  pkg 0402  page 234 : 1 = P3V3_AUX ; 2 = GND
C1797  Q_CAP  0.1UF 25V 10% X7R  pkg 0402  page 301 : 1 = PDB_PRSNT_N ; 2 = GND
C1802  Q_CAP  1000PF 50V 5% EMPTY  pkg 0402  page 148 : 1 = FM_SMB_1_ALERT_GPU_ISO_N ; 2 = GND
C1803  Q_CAP  0.1UF 25V 10% X7R  pkg 0402  page 151 : 1 = P3V3_AUX ; 2 = GND
C1804  Q_CAP  1000PF 50V 5% EMPTY  pkg 0402  page 148 : 1 = FM_SMB_2_ALERT_GPU_ISO_N ; 2 = GND
C1809  Q_CAP  0.1UF 25V 10% X7R  pkg 0402  page 162 : 1 = P3V3_AUX ; 2 = GND
C1810  Q_CAP  0.1UF 25V 10% X7R  pkg 0402  page 162 : 1 = P3V3_AUX ; 2 = GND
C1817  Q_CAP  0.1UF 25V 10% X7R  pkg 0402  page 164 : 1 = P3V3_AUX ; 2 = GND
C1818  Q_CAP  0.1UF 25V 10% X7R  pkg 0402  page 164 : 1 = P3V3_AUX ; 2 = GND
C1819  Q_CAP  0.1UF 25V 10% X7R  pkg 0402  page 164 : 1 = P3V3_OCP_V3_2 ; 2 = GND
C1820  Q_CAP  0.1UF 25V 10% X7R  pkg 0402  page 164 : 1 = P3V3_AUX ; 2 = GND
C1821  Q_CAP  0.1UF 25V 10% X7R  pkg 0402  page 161 : 1 = P3V3_AUX ; 2 = GND
C1822  Q_CAP  0.1UF 25V 10% X7R  pkg 0402  page 161 : 1 = P3V3_AUX ; 2 = GND
C1823  Q_CAP  0.1UF 25V 10% X7R  pkg 0402  page 161 : 1 = P3V3_AUX ; 2 = GND
C1824  Q_CAP  0.1UF 25V 10% X7R  pkg 0402  page 161 : 1 = P3V3_AUX ; 2 = GND
C1825  Q_CAP  0.1UF 25V 10% X7R  pkg 0402  page 160 : 1 = P3V3_AUX ; 2 = GND
C1826  Q_CAP  0.1UF 25V 10% X7R  pkg 0402  page 160 : 1 = P3V3_AUX ; 2 = GND
C1827  Q_CAP  0.1UF 25V 10% X7R  pkg 0402  page 160 : 1 = P3V3_AUX ; 2 = GND
C1829  Q_CAP  22UF 16V 20% X6S  pkg C0805  page 159 : 1 = P12V_OCP_V3_2 ; 2 = GND
C1830  Q_CAP  22UF 16V 20% X6S  pkg C0805  page 159 : 1 = P12V_OCP_V3_2 ; 2 = GND
C1831  Q_CAP  0.1UF 25V 10% X7R  pkg 0402  page 159 : 1 = P12V_OCP_V3_2 ; 2 = GND
C1832  Q_CAP  0.1UF 25V 10% X7R  pkg 0402  page 159 : 1 = P12V_OCP_V3_2 ; 2 = GND
C1833  Q_CAP  0.1UF 25V 10% X7R  pkg 0402  page 159 : 1 = P12V_OCP_V3_2 ; 2 = GND
C1834  Q_CAP  0.1UF 25V 10% X7R  pkg 0402  page 159 : 1 = P12V_OCP_V3_2 ; 2 = GND
C1835  Q_CAP  0.1UF 25V 10% X7R  pkg 0402  page 159 : 1 = P3V3_OCP_V3_2 ; 2 = GND
C1836  Q_CAP  0.1UF 25V 10% X7R  pkg 0402  page 159 : 1 = P3V3_OCP_V3_2 ; 2 = GND
C1837  Q_CAP  0.1UF 25V 10% X7R  pkg 0402  page 159 : 1 = P3V3_OCP_V3_2 ; 2 = GND
C1838  Q_CAP  0.1UF 25V 10% X7R  pkg 0402  page 159 : 1 = P3V3_OCP_V3_2 ; 2 = GND
C1839  Q_CAP  0.1UF 25V 10% X7R  pkg 0402  page 159 : 1 = P12V_OCP_V3_2 ; 2 = GND
C1840  Q_CAP  0.1UF 25V 10% X7R  pkg 0402  page 154 : 1 = P3V3_AUX ; 2 = GND
C1841  Q_CAP  0.1UF 25V 10% X7R  pkg 0402  page 161 : 1 = P3V3_AUX ; 2 = GND
C1842  Q_CAP  10UF 6.3V 20% X6S  pkg C0402  page 217 : 1 = P3V3_AUX_FPGA_VCCIO3 ; 2 = GND
C1859  Q_CAP  0.1UF 25V 10% X7R  pkg 0402  page 238 : 1 = P3V3_AUX ; 2 = GND
C1860  Q_CAP  0.1UF 25V 10% X7R  pkg 0402  page 238 : 1 = P3V3_AUX ; 2 = GND
C1861  Q_CAP  0.1UF 25V 10% X7R  pkg 0402  page 238 : 1 = P3V3_OCP_V3_2 ; 2 = GND
C1862  Q_CAP  0.1UF 25V 10% X7R  pkg 0402  page 238 : 1 = P3V3_OCP_SFF ; 2 = GND
C1863  Q_CAP  0.1UF 25V 10% X7R  pkg 0402  page 166 : 1 = P3V3_AUX ; 2 = GND
C1864  Q_CAP  0.1UF 25V 10% X7R  pkg 0402  page 166 : 1 = P3V3_AUX ; 2 = GND
C1865  Q_CAP  0.1UF 25V 10% X7R  pkg 0402  page 166 : 1 = P3V3_AUX ; 2 = GND
C1866  Q_CAP  0.1UF 25V 10% X7R  pkg 0402  page 166 : 1 = P3V3_AUX ; 2 = GND
C1867  Q_CAP  10UF 25V 10% X6S  pkg C0805  page 166 : 1 = P3V3_AUX ; 2 = GND
C1868  Q_CAP  0.1UF 25V 10% X7R  pkg 0402  page 167 : 1 = P2E_MB_BMC_RX_BUF_C_DP<0> ; 2 = P2E_MB_BMC_RX_BUF_DP<0>
